FILE_TYPE = CONNECTIVITY;
{Allegro Design Entry HDL 17.2-2016 S081 (4005846) 1/11/2022}
"PAGE_NUMBER" = 34;
0"NC";
1"GND\g";
2"GND\g";
3"GND\g";
4"GND\g";
5"GND\g";
6"P1V8_STBY\g";
7"GND\g";
8"GND\g";
9"SLOT1_SKU_ID0";
10"SLOT1_SKU_ID1";
11"SMB_CPU0_4_SCL";
12"SMB_CPU0_4_SDA";
13"FM_BIOS_POST_CMPLT_N";
14"PVDD18_S5_P0\g";
15"SLOT1_BUF_SKU_ID1";
16"FM_BIOS_POST_CMPLT_BUF_N";
17"P3V3_STBY\g";
18"TP_U27_EN";
19"P3V3_STBY\g";
20"PVDD18_S5_P0\g";
21"SLOT1_BUF_SKU_ID0";
22"SMB_CPU0_4_XLTR_SCL";
23"SMB_CPU0_4_XLTR_SDA";
24"PVDD18_S5_P0\g";
25"P3V3_STBY\g";
26"SMB_CPU0_4_XLTR_SDA";
27"SMB_CPU0_4_SCL";
28"SMB_CPU0_4_SDA";
29"SLOT1_BUF_SKU_ID0";
30"SLOT1_BUF_SKU_ID1";
31"SMB_CPU0_4_XLTR_SCL";
%"Q_RES"
"1","(-1625,4925)","0","pure_quanta","I106";
;
LOCATION"R495"
$SEC"1"
CDS_SEC"1"
VALUE"4.7K"
CDS_LIB"pure_quanta"
WATTAGE"1/16W"
MATERIAL"CHIP"
TOLERANCE"5%"
PART_NUMBER"TMP_QCS24702JB38"
PACK_TYPE"0402LF";
"B"
$PN"2"27;
"A"
$PN"1"24;
%"Q_RES"
"1","(-1625,4850)","0","pure_quanta","I107";
;
LOCATION"R498"
$SEC"1"
CDS_SEC"1"
VALUE"4.7K"
CDS_LIB"pure_quanta"
WATTAGE"1/16W"
MATERIAL"CHIP"
TOLERANCE"5%"
PART_NUMBER"TMP_QCS24702JB38"
PACK_TYPE"0402LF";
"B"
$PN"2"28;
"A"
$PN"1"24;
%"UNIVERSAL_POWER"
"1","(-2025,5400)","2","pure_quanta_power","I108";
;
HDL_POWER"PVDD18_S5_P0"
CDS_LIB"pure_quanta_power";
"A"24;
%"Q_RES"
"1","(-1625,5200)","0","pure_quanta","I111";
;
LOCATION"R650"
$SEC"1"
CDS_SEC"1"
VALUE"4.7K"
CDS_LIB"pure_quanta"
WATTAGE"1/16W"
MATERIAL"CHIP"
TOLERANCE"5%"
PART_NUMBER"TMP_QCS24702JB38"
PACK_TYPE"0402LF";
"B"
$PN"2"29;
"A"
$PN"1"24;
%"Q_RES"
"1","(-1625,5100)","0","pure_quanta","I112";
;
LOCATION"R651"
$SEC"1"
CDS_SEC"1"
VALUE"4.7K"
CDS_LIB"pure_quanta"
WATTAGE"1/16W"
MATERIAL"CHIP"
TOLERANCE"5%"
PART_NUMBER"TMP_QCS24702JB38"
PACK_TYPE"0402LF";
"B"
$PN"2"30;
"A"
$PN"1"24;
%"PCA9617ADP"
"1","(-7200,5575)","0","pure_quanta","I18";
;
LOCATION"U27"
$SEC"1"
CDS_SEC"1"
PART_TYPE"SMLF"
MATERIAL"IC"
VALUE"PCA9617ADP"
PART_NUMBER"AL009617K02"
NEEDS_NO_SIZE"TRUE"
CDS_LMAN_SYM_OUTLINE"-275,300,275,-300"
CDS_LIB"pure_quanta";
"GND"
$PN"4"3;
"SCLB"
$PN"7"22;
"SDAB"
$PN"6"23;
"SDAA"
$PN"3"12;
"SCLA"
$PN"2"11;
"VCCB"
$PN"8"19;
"VCCA"
$PN"1"20;
"EN"
$PN"5"18;
%"UNIVERSAL_GND"
"1","(-6750,4225)","0","pure_quanta_power","I28";
;
CDS_LIB"pure_quanta_power"
HDL_POWER"GND";
"A"1;
%"Q_CAP"
"1","(-6750,4425)","0","pure_quanta","I29";
;
LOCATION"C225"
$SEC"1"
CDS_SEC"1"
MATERIAL"X7R"
TOLERANCE"10%"
VALUE"0.1UF"
VOLTAGE"25V"
PACK_TYPE"0402"
CDS_LIB"pure_quanta"
PART_NUMBER"CH4104K1B00";
"B"
$PN"2"1;
"A"
$PN"1"17;
%"UNIVERSAL_POWER"
"1","(-2025,6475)","2","pure_quanta_power","I3";
;
HDL_POWER"P3V3_STBY"
CDS_LIB"pure_quanta_power";
"A"25;
%"UNIVERSAL_POWER"
"1","(-6825,4750)","2","pure_quanta_power","I31";
;
HDL_POWER"P3V3_STBY"
CDS_LIB"pure_quanta_power";
"A"17;
%"SN74LVC2G07DCKR"
"1","(-7300,4125)","0","pure_quanta","I32";
;
LOCATION"U11"
$SEC"1"
CDS_SEC"1"
MATERIAL"IC"
VALUE"SN74LVC2G07DCKR"
PART_NUMBER"AL002G07006"
PACK_TYPE"SMLF"
CDS_LIB"pure_quanta"
NEEDS_NO_SIZE"TRUE";
"VCC"
$PN"5"17;
"GND"
$PN"2"2;
"2Y"
$PN"4"15;
"1Y"
$PN"6"21;
"2A"
$PN"3"10;
"1A"
$PN"1"9;
%"UNIVERSAL_GND"
"1","(-7725,4125)","5","pure_quanta_power","I33";
;
CDS_LIB"pure_quanta_power"
HDL_POWER"GND";
"A"2;
%"Q_RES"
"1","(-1675,6000)","0","pure_quanta","I4";
;
LOCATION"R499"
$SEC"1"
CDS_SEC"1"
VALUE"4.7K"
CDS_LIB"pure_quanta"
WATTAGE"1/16W"
MATERIAL"CHIP"
TOLERANCE"5%"
PART_NUMBER"TMP_QCS24702JB38"
PACK_TYPE"0402LF";
"B"
$PN"2"31;
"A"
$PN"1"25;
%"UNIVERSAL_GND"
"1","(-7775,5175)","0","pure_quanta_power","I40";
;
CDS_LIB"pure_quanta_power"
HDL_POWER"GND";
"A"3;
%"UNIVERSAL_POWER"
"1","(-7700,6300)","2","pure_quanta_power","I43";
;
HDL_POWER"PVDD18_S5_P0"
CDS_LIB"pure_quanta_power";
"A"20;
%"Q_CAP"
"1","(-7875,6025)","0","pure_quanta","I44";
;
LOCATION"C42"
$SEC"1"
CDS_SEC"1"
MATERIAL"X7R"
TOLERANCE"10%"
VALUE"0.1UF"
VOLTAGE"25V"
PACK_TYPE"0402"
CDS_LIB"pure_quanta"
PART_NUMBER"CH4104K1B00";
"B"
$PN"2"4;
"A"
$PN"1"20;
%"UNIVERSAL_GND"
"1","(-7875,5825)","0","pure_quanta_power","I45";
;
CDS_LIB"pure_quanta_power"
HDL_POWER"GND";
"A"4;
%"UNIVERSAL_POWER"
"1","(-6625,6350)","2","pure_quanta_power","I46";
;
HDL_POWER"P3V3_STBY"
CDS_LIB"pure_quanta_power";
"A"19;
%"Q_CAP"
"1","(-6550,6025)","0","pure_quanta","I47";
;
LOCATION"C43"
$SEC"1"
CDS_SEC"1"
MATERIAL"X7R"
TOLERANCE"10%"
VALUE"0.1UF"
VOLTAGE"25V"
PACK_TYPE"0402"
CDS_LIB"pure_quanta"
PART_NUMBER"CH4104K1B00";
"B"
$PN"2"5;
"A"
$PN"1"19;
%"UNIVERSAL_GND"
"1","(-6550,5825)","0","pure_quanta_power","I48";
;
CDS_LIB"pure_quanta_power"
HDL_POWER"GND";
"A"5;
%"Q_RES"
"1","(-1675,5925)","0","pure_quanta","I5";
;
LOCATION"R590"
$SEC"1"
CDS_SEC"1"
VALUE"4.7K"
CDS_LIB"pure_quanta"
WATTAGE"1/16W"
MATERIAL"CHIP"
TOLERANCE"5%"
PART_NUMBER"TMP_QCS24702JB38"
PACK_TYPE"0402LF";
"B"
$PN"2"26;
"A"
$PN"1"25;
%"Q_RES"
"2","(-5400,2975)","0","pure_quanta","I53";
;
LOCATION"R943"
$SEC"1"
CDS_SEC"1"
WATTAGE"1/16W"
MATERIAL"CHIP"
TOLERANCE"5%"
VALUE"4.7K"
PART_NUMBER"TMP_QCS24702JB38"
PACK_TYPE"0402LF"
CDS_LIB"pure_quanta"
BOM_COST"OCP3.0 ";
"A"
$PN"1"6;
"B"
$PN"2"16;
%"UNIVERSAL_POWER"
"1","(-5400,3250)","0","pure_quanta_power","I54";
;
HDL_POWER"P1V8_STBY"
BOM_COST"OCP3.0 "
CDS_LIB"pure_quanta_power";
"A"6;
%"SN74LVC1G07DBVR"
"1","(-6350,2725)","0","pure_quanta","I55";
;
LOCATION"U101"
$SEC"1"
CDS_SEC"1"
MATERIAL"IC"
VALUE"SN74LVC1G07DBVR"
PART_NUMBER"AL1G0007024"
PACK_TYPE"SMLF"
CDS_LIB"pure_quanta"
NEEDS_NO_SIZE"TRUE";
"NC"
$PN"1"0;
"Y"
$PN"4"16;
"GND"
$PN"3"7;
"A"
$PN"2"13;
"VCC"
$PN"5"14;
%"UNIVERSAL_GND"
"1","(-6600,2450)","0","pure_quanta_power","I56";
;
BOM_COST"OCP3.0 "
CDS_LIB"pure_quanta_power"
HDL_POWER"GND";
"A"7;
%"UNIVERSAL_GND"
"1","(-6950,2850)","0","pure_quanta_power","I58";
;
BOM_COST"OCP3.0 "
CDS_LIB"pure_quanta_power"
HDL_POWER"GND";
"A"8;
%"Q_CAP"
"1","(-6950,3050)","0","pure_quanta","I59";
;
LOCATION"C226"
$SEC"1"
CDS_SEC"1"
MATERIAL"X7R"
TOLERANCE"10%"
VALUE"0.1UF"
PART_NUMBER"CH4104K1B00"
VOLTAGE"25V"
PACK_TYPE"0402"
CDS_LIB"pure_quanta"
BOM_COST"OCP3.0 ";
"B"
$PN"2"8;
"A"
$PN"1"14;
%"Q_RES"
"2","(-7075,3050)","2","pure_quanta","I60";
;
LOCATION"R942"
$SEC"1"
CDS_SEC"1"
WATTAGE"1/16W"
MATERIAL"CHIP"
TOLERANCE"5%"
VALUE"4.7K"
PART_NUMBER"TMP_QCS24702JB38"
PACK_TYPE"0402LF"
CDS_LIB"pure_quanta"
BOM_COST"OCP3.0 ";
"A"
$PN"1"14;
"B"
$PN"2"13;
%"P1V0"
"1","(-6950,3350)","0","pure_quanta_power","I62";
;
HDL_POWER"PVDD18_S5_P0"
CDS_LIB"pure_quanta_power";
"A"14;
END.
